(kicad_pcb
	(version 20260206)
	(generator "pcbnew")
	(generator_version "10.0")
	(general
		(thickness 1.6)
		(legacy_teardrops no)
	)
	(paper "A4")
	(title_block
		(title "Bryce Canyon_R.DPB_16317-1_OCP.brd")
		(comment 1 "Bryce Canyon / footprints 1290-1295 of 2099")
	)
	(layers
		(0 "F.Cu" signal "TOP")
		(4 "In1.Cu" signal "L2GND")
		(6 "In2.Cu" signal "L3")
		(8 "In3.Cu" signal "L4VCC")
		(10 "In4.Cu" signal "L5VCC")
		(12 "In5.Cu" signal "L6")
		(14 "In6.Cu" signal "L7GND")
		(2 "B.Cu" signal "BOTTOM")
		(9 "F.Adhes" user "F.Adhesive")
		(11 "B.Adhes" user "B.Adhesive")
		(13 "F.Paste" user "Package Geometry/Pastemask Top")
		(15 "B.Paste" user "Package Geometry/Pastemask Bottom")
		(5 "F.SilkS" user "Ref Des/Silkscreen Top")
		(7 "B.SilkS" user "Ref Des/Silkscreen Bottom")
		(1 "F.Mask" user "Board Geometry/Soldermask Top")
		(3 "B.Mask" user "Board Geometry/Soldermask Bottom")
		(17 "Dwgs.User" user "User.Drawings")
		(19 "Cmts.User" user "User.Comments")
		(21 "Eco1.User" user "User.Eco1")
		(23 "Eco2.User" user "User.Eco2")
		(25 "Edge.Cuts" user "Board Geometry/Outline")
		(27 "Margin" user)
		(31 "F.CrtYd" user "Package Geometry/Place Bound Top")
		(29 "B.CrtYd" user "Package Geometry/Place Bound Bottom")
		(35 "F.Fab" user "Ref Des/Assembly Top")
		(33 "B.Fab" user "Ref Des/Assembly Bottom")
	)
	(footprint ""
		(layer "F.Cu")
		(at 457.553568 -99.950778 90)
		(property "Reference" "Q264"
			(at 0 0 90)
			(layer "F.SilkS")
			(hide yes)
			(effects
				(font
					(size 1.27 1.27)
				)
			)
		)
		(property "Value" "SSM3K324R-GP"
			(at 0.127 -8.9662 90)
			(unlocked yes)
			(layer "F.Fab")
			(hide yes)
			(effects
				(font
					(size 1.016 1.016)
					(thickness 0.1524)
				)
			)
		)
		(property "Device Type" "SOT23DGS2D4H35"
			(at 0.127 -10.4902 90)
			(unlocked yes)
			(layer "F.Fab")
			(hide yes)
			(effects
				(font
					(size 1.016 1.016)
					(thickness 0.1524)
				)
			)
		)
		(duplicate_pad_numbers_are_jumpers no)
		(fp_line
			(start 1.651 -1.778)
			(end -1.651 -1.778)
			(stroke
				(width 0.1524)
				(type default)
			)
			(layer "F.SilkS")
		)
		(fp_line
			(start -1.651 -1.778)
			(end -1.651 1.778)
			(stroke
				(width 0.1524)
				(type default)
			)
			(layer "F.SilkS")
		)
		(fp_line
			(start 1.651 1.778)
			(end 1.651 -1.778)
			(stroke
				(width 0.1524)
				(type default)
			)
			(layer "F.SilkS")
		)
		(fp_line
			(start -1.651 1.778)
			(end 1.651 1.778)
			(stroke
				(width 0.1524)
				(type default)
			)
			(layer "F.SilkS")
		)
		(fp_poly
			(pts
				(xy -1.778 1.8796) (xy -1.778 -1.8796) (xy 1.778 -1.8796) (xy 1.778 1.8796)
			)
			(stroke
				(width 0)
				(type default)
			)
			(fill no)
			(layer "F.CrtYd")
		)
		(fp_poly
			(pts
				(xy -1.778 1.8796) (xy -1.778 -1.8796) (xy 1.778 -1.8796) (xy 1.778 1.8796)
			)
			(stroke
				(width 0)
				(type default)
			)
			(fill no)
			(layer "F.Fab")
		)
		(pad "D" smd custom
			(at 0 -0.9525 90)
			(size 0.1905 0.1905)
			(layers "F.Cu" "F.Mask" "F.Paste")
			(net "DRV_ACT_23_N")
			(options
				(clearance outline)
				(anchor circle)
			)
			(primitives
				(gr_poly
					(pts
						(arc
							(start -0.1778 0.5715)
							(mid -0.321484 0.511984)
							(end -0.381 0.3683)
						)
						(arc
							(start -0.381 -0.3683)
							(mid -0.321484 -0.511984)
							(end -0.1778 -0.5715)
						)
						(arc
							(start 0.1778 -0.5715)
							(mid 0.321484 -0.511984)
							(end 0.381 -0.3683)
						)
						(arc
							(start 0.381 0.3683)
							(mid 0.321484 0.511984)
							(end 0.1778 0.5715)
						)
					)
					(width 0)
					(fill yes)
				)
			)
		)
		(pad "G" smd custom
			(at -0.98425 0.9525 90)
			(size 0.1905 0.1905)
			(layers "F.Cu" "F.Mask" "F.Paste")
			(net "DRIVE_B_23_ACT")
			(options
				(clearance outline)
				(anchor circle)
			)
			(primitives
				(gr_poly
					(pts
						(arc
							(start -0.1778 0.5715)
							(mid -0.321484 0.511984)
							(end -0.381 0.3683)
						)
						(arc
							(start -0.381 -0.3683)
							(mid -0.321484 -0.511984)
							(end -0.1778 -0.5715)
						)
						(arc
							(start 0.1778 -0.5715)
							(mid 0.321484 -0.511984)
							(end 0.381 -0.3683)
						)
						(arc
							(start 0.381 0.3683)
							(mid 0.321484 0.511984)
							(end 0.1778 0.5715)
						)
					)
					(width 0)
					(fill yes)
				)
			)
		)
		(pad "S" smd custom
			(at 0.98425 0.9525 90)
			(size 0.1905 0.1905)
			(layers "F.Cu" "F.Mask" "F.Paste")
			(net "GND")
			(options
				(clearance outline)
				(anchor circle)
			)
			(primitives
				(gr_poly
					(pts
						(arc
							(start -0.1778 0.5715)
							(mid -0.321484 0.511984)
							(end -0.381 0.3683)
						)
						(arc
							(start -0.381 -0.3683)
							(mid -0.321484 -0.511984)
							(end -0.1778 -0.5715)
						)
						(arc
							(start 0.1778 -0.5715)
							(mid 0.321484 -0.511984)
							(end 0.381 -0.3683)
						)
						(arc
							(start 0.381 0.3683)
							(mid 0.321484 0.511984)
							(end 0.1778 0.5715)
						)
					)
					(width 0)
					(fill yes)
				)
			)
		)
	)
	(footprint ""
		(layer "F.Cu")
		(at 431.546 -16.764 180)
		(property "Reference" "R842"
			(at 0 0 180)
			(layer "F.SilkS")
			(hide yes)
			(effects
				(font
					(size 1.27 1.27)
				)
			)
		)
		(property "Value" "4K7R2J-2-GP"
			(at 0.064008 -3.993896 180)
			(unlocked yes)
			(layer "F.Fab")
			(hide yes)
			(effects
				(font
					(size 1.016 1.016)
					(thickness 0.1524)
				)
			)
		)
		(property "Device Type" "R402H16"
			(at 0.064008 -5.517896 180)
			(unlocked yes)
			(layer "F.Fab")
			(hide yes)
			(effects
				(font
					(size 1.016 1.016)
					(thickness 0.1524)
				)
			)
		)
		(duplicate_pad_numbers_are_jumpers no)
		(fp_line
			(start 0.508 -0.9398)
			(end -0.508 -0.9398)
			(stroke
				(width 0.1524)
				(type default)
			)
			(layer "F.SilkS")
		)
		(fp_line
			(start -0.508 -0.9398)
			(end -0.508 0.9398)
			(stroke
				(width 0.1524)
				(type default)
			)
			(layer "F.SilkS")
		)
		(fp_rect
			(start -0.508 0.9398)
			(end 0.508 -0.9398)
			(stroke
				(width 0)
				(type default)
			)
			(fill no)
			(layer "F.CrtYd")
		)
		(fp_rect
			(start -0.508 0.9398)
			(end 0.508 -0.9398)
			(stroke
				(width 0)
				(type default)
			)
			(fill no)
			(layer "F.Fab")
		)
		(pad "1" smd custom
			(at 0 -0.4445 180)
			(size 0.1397 0.1397)
			(layers "F.Cu" "F.Mask" "F.Paste")
			(net "P12V_B")
			(options
				(clearance outline)
				(anchor circle)
			)
			(primitives
				(gr_poly
					(pts
						(arc
							(start -0.1778 -0.2794)
							(mid -0.249642 -0.249642)
							(end -0.2794 -0.1778)
						)
						(arc
							(start -0.2794 0.1778)
							(mid -0.249642 0.249642)
							(end -0.1778 0.2794)
						)
						(arc
							(start 0.1778 0.2794)
							(mid 0.249642 0.249642)
							(end 0.2794 0.1778)
						)
						(arc
							(start 0.2794 -0.1778)
							(mid 0.249642 -0.249642)
							(end 0.1778 -0.2794)
						)
					)
					(width 0)
					(fill yes)
				)
			)
		)
		(pad "2" smd custom
			(at 0 0.4445 180)
			(size 0.1397 0.1397)
			(layers "F.Cu" "F.Mask" "F.Paste")
			(net "SW_HDD_R33")
			(options
				(clearance outline)
				(anchor circle)
			)
			(primitives
				(gr_poly
					(pts
						(arc
							(start -0.1778 -0.2794)
							(mid -0.249642 -0.249642)
							(end -0.2794 -0.1778)
						)
						(arc
							(start -0.2794 0.1778)
							(mid -0.249642 0.249642)
							(end -0.1778 0.2794)
						)
						(arc
							(start 0.1778 0.2794)
							(mid 0.249642 0.249642)
							(end 0.2794 0.1778)
						)
						(arc
							(start 0.2794 -0.1778)
							(mid 0.249642 -0.249642)
							(end 0.1778 -0.2794)
						)
					)
					(width 0)
					(fill yes)
				)
			)
		)
	)
	(footprint ""
		(layer "F.Cu")
		(at 209.03946 -167.43426 -90)
		(property "Reference" "R53"
			(at 0 0 270)
			(layer "F.SilkS")
			(hide yes)
			(effects
				(font
					(size 1.27 1.27)
				)
			)
		)
		(property "Value" "4K7R2F-GP"
			(at 0.064008 -3.993896 270)
			(unlocked yes)
			(layer "F.Fab")
			(hide yes)
			(effects
				(font
					(size 1.016 1.016)
					(thickness 0.1524)
				)
			)
		)
		(property "Device Type" "R402H16"
			(at 0.064008 -5.517896 270)
			(unlocked yes)
			(layer "F.Fab")
			(hide yes)
			(effects
				(font
					(size 1.016 1.016)
					(thickness 0.1524)
				)
			)
		)
		(duplicate_pad_numbers_are_jumpers no)
		(fp_line
			(start -0.508 -0.9398)
			(end -0.508 0.9398)
			(stroke
				(width 0.1524)
				(type default)
			)
			(layer "F.SilkS")
		)
		(fp_line
			(start 0.508 -0.9398)
			(end -0.508 -0.9398)
			(stroke
				(width 0.1524)
				(type default)
			)
			(layer "F.SilkS")
		)
		(fp_rect
			(start -0.508 0.9398)
			(end 0.508 -0.9398)
			(stroke
				(width 0)
				(type default)
			)
			(fill no)
			(layer "F.CrtYd")
		)
		(fp_rect
			(start -0.508 0.9398)
			(end 0.508 -0.9398)
			(stroke
				(width 0)
				(type default)
			)
			(fill no)
			(layer "F.Fab")
		)
		(pad "1" smd custom
			(at 0 -0.4445 270)
			(size 0.1397 0.1397)
			(layers "F.Cu" "F.Mask" "F.Paste")
			(net "IO_EXP6_A0")
			(options
				(clearance outline)
				(anchor circle)
			)
			(primitives
				(gr_poly
					(pts
						(arc
							(start -0.1778 -0.2794)
							(mid -0.249642 -0.249642)
							(end -0.2794 -0.1778)
						)
						(arc
							(start -0.2794 0.1778)
							(mid -0.249642 0.249642)
							(end -0.1778 0.2794)
						)
						(arc
							(start 0.1778 0.2794)
							(mid 0.249642 0.249642)
							(end 0.2794 0.1778)
						)
						(arc
							(start 0.2794 -0.1778)
							(mid 0.249642 -0.249642)
							(end 0.1778 -0.2794)
						)
					)
					(width 0)
					(fill yes)
				)
			)
		)
		(pad "2" smd custom
			(at 0 0.4445 270)
			(size 0.1397 0.1397)
			(layers "F.Cu" "F.Mask" "F.Paste")
			(net "GND")
			(options
				(clearance outline)
				(anchor circle)
			)
			(primitives
				(gr_poly
					(pts
						(arc
							(start -0.1778 -0.2794)
							(mid -0.249642 -0.249642)
							(end -0.2794 -0.1778)
						)
						(arc
							(start -0.2794 0.1778)
							(mid -0.249642 0.249642)
							(end -0.1778 0.2794)
						)
						(arc
							(start 0.1778 0.2794)
							(mid 0.249642 0.249642)
							(end 0.2794 0.1778)
						)
						(arc
							(start 0.2794 -0.1778)
							(mid 0.249642 -0.249642)
							(end 0.1778 -0.2794)
						)
					)
					(width 0)
					(fill yes)
				)
			)
		)
	)
	(footprint ""
		(layer "F.Cu")
		(at 174.498 -253.111 90)
		(property "Reference" "R243"
			(at 0 0 90)
			(layer "F.SilkS")
			(hide yes)
			(effects
				(font
					(size 1.27 1.27)
				)
			)
		)
		(property "Value" "4K7R2J-2-GP"
			(at 0.064008 -3.993896 90)
			(unlocked yes)
			(layer "F.Fab")
			(hide yes)
			(effects
				(font
					(size 1.016 1.016)
					(thickness 0.1524)
				)
			)
		)
		(property "Device Type" "R402H16"
			(at 0.064008 -5.517896 90)
			(unlocked yes)
			(layer "F.Fab")
			(hide yes)
			(effects
				(font
					(size 1.016 1.016)
					(thickness 0.1524)
				)
			)
		)
		(duplicate_pad_numbers_are_jumpers no)
		(fp_line
			(start 0.508 -0.9398)
			(end -0.508 -0.9398)
			(stroke
				(width 0.1524)
				(type default)
			)
			(layer "F.SilkS")
		)
		(fp_line
			(start -0.508 -0.9398)
			(end -0.508 0.9398)
			(stroke
				(width 0.1524)
				(type default)
			)
			(layer "F.SilkS")
		)
		(fp_rect
			(start -0.508 0.9398)
			(end 0.508 -0.9398)
			(stroke
				(width 0)
				(type default)
			)
			(fill no)
			(layer "F.CrtYd")
		)
		(fp_rect
			(start -0.508 0.9398)
			(end 0.508 -0.9398)
			(stroke
				(width 0)
				(type default)
			)
			(fill no)
			(layer "F.Fab")
		)
		(pad "1" smd custom
			(at 0 -0.4445 90)
			(size 0.1397 0.1397)
			(layers "F.Cu" "F.Mask" "F.Paste")
			(net "P12V_B")
			(options
				(clearance outline)
				(anchor circle)
			)
			(primitives
				(gr_poly
					(pts
						(arc
							(start -0.1778 -0.2794)
							(mid -0.249642 -0.249642)
							(end -0.2794 -0.1778)
						)
						(arc
							(start -0.2794 0.1778)
							(mid -0.249642 0.249642)
							(end -0.1778 0.2794)
						)
						(arc
							(start 0.1778 0.2794)
							(mid 0.249642 0.249642)
							(end 0.2794 0.1778)
						)
						(arc
							(start 0.2794 -0.1778)
							(mid 0.249642 -0.249642)
							(end 0.1778 -0.2794)
						)
					)
					(width 0)
					(fill yes)
				)
			)
		)
		(pad "2" smd custom
			(at 0 0.4445 90)
			(size 0.1397 0.1397)
			(layers "F.Cu" "F.Mask" "F.Paste")
			(net "SW_HDD_P5")
			(options
				(clearance outline)
				(anchor circle)
			)
			(primitives
				(gr_poly
					(pts
						(arc
							(start -0.1778 -0.2794)
							(mid -0.249642 -0.249642)
							(end -0.2794 -0.1778)
						)
						(arc
							(start -0.2794 0.1778)
							(mid -0.249642 0.249642)
							(end -0.1778 0.2794)
						)
						(arc
							(start 0.1778 0.2794)
							(mid 0.249642 0.249642)
							(end 0.2794 0.1778)
						)
						(arc
							(start 0.2794 -0.1778)
							(mid 0.249642 -0.249642)
							(end 0.1778 -0.2794)
						)
					)
					(width 0)
					(fill yes)
				)
			)
		)
	)
	(footprint ""
		(layer "F.Cu")
		(at 336.931 -246.761 180)
		(property "Reference" "R264"
			(at 0 0 180)
			(layer "F.SilkS")
			(hide yes)
			(effects
				(font
					(size 1.27 1.27)
				)
			)
		)
		(property "Value" "4K7R2J-2-GP"
			(at 0.064008 -3.993896 180)
			(unlocked yes)
			(layer "F.Fab")
			(hide yes)
			(effects
				(font
					(size 1.016 1.016)
					(thickness 0.1524)
				)
			)
		)
		(property "Device Type" "R402H16"
			(at 0.064008 -5.517896 180)
			(unlocked yes)
			(layer "F.Fab")
			(hide yes)
			(effects
				(font
					(size 1.016 1.016)
					(thickness 0.1524)
				)
			)
		)
		(duplicate_pad_numbers_are_jumpers no)
		(fp_line
			(start 0.508 -0.9398)
			(end -0.508 -0.9398)
			(stroke
				(width 0.1524)
				(type default)
			)
			(layer "F.SilkS")
		)
		(fp_line
			(start -0.508 -0.9398)
			(end -0.508 0.9398)
			(stroke
				(width 0.1524)
				(type default)
			)
			(layer "F.SilkS")
		)
		(fp_rect
			(start -0.508 0.9398)
			(end 0.508 -0.9398)
			(stroke
				(width 0)
				(type default)
			)
			(fill no)
			(layer "F.CrtYd")
		)
		(fp_rect
			(start -0.508 0.9398)
			(end 0.508 -0.9398)
			(stroke
				(width 0)
				(type default)
			)
			(fill no)
			(layer "F.Fab")
		)
		(pad "1" smd custom
			(at 0 -0.4445 180)
			(size 0.1397 0.1397)
			(layers "F.Cu" "F.Mask" "F.Paste")
			(net "P12V_B")
			(options
				(clearance outline)
				(anchor circle)
			)
			(primitives
				(gr_poly
					(pts
						(arc
							(start -0.1778 -0.2794)
							(mid -0.249642 -0.249642)
							(end -0.2794 -0.1778)
						)
						(arc
							(start -0.2794 0.1778)
							(mid -0.249642 0.249642)
							(end -0.1778 0.2794)
						)
						(arc
							(start 0.1778 0.2794)
							(mid 0.249642 0.249642)
							(end 0.2794 0.1778)
						)
						(arc
							(start 0.2794 -0.1778)
							(mid 0.249642 -0.249642)
							(end 0.1778 -0.2794)
						)
					)
					(width 0)
					(fill yes)
				)
			)
		)
		(pad "2" smd custom
			(at 0 0.4445 180)
			(size 0.1397 0.1397)
			(layers "F.Cu" "F.Mask" "F.Paste")
			(net "SW_HDD_R6")
			(options
				(clearance outline)
				(anchor circle)
			)
			(primitives
				(gr_poly
					(pts
						(arc
							(start -0.1778 -0.2794)
							(mid -0.249642 -0.249642)
							(end -0.2794 -0.1778)
						)
						(arc
							(start -0.2794 0.1778)
							(mid -0.249642 0.249642)
							(end -0.1778 0.2794)
						)
						(arc
							(start 0.1778 0.2794)
							(mid 0.249642 0.249642)
							(end 0.2794 0.1778)
						)
						(arc
							(start 0.2794 -0.1778)
							(mid 0.249642 -0.249642)
							(end 0.1778 -0.2794)
						)
					)
					(width 0)
					(fill yes)
				)
			)
		)
	)
	(footprint ""
		(layer "F.Cu")
		(at 178.435 -141.224 180)
		(property "Reference" "Q75"
			(at 0 0 180)
			(layer "F.SilkS")
			(hide yes)
			(effects
				(font
					(size 1.27 1.27)
				)
			)
		)
		(property "Value" "AO4406AL-GP"
			(at -3.707384 -1.5367 180)
			(unlocked yes)
			(layer "F.Fab")
			(hide yes)
			(effects
				(font
					(size 1.016 1.016)
					(thickness 0.1524)
				)
			)
		)
		(property "Device Type" "SOIC8H69"
			(at -3.707384 -3.0607 180)
			(unlocked yes)
			(layer "F.Fab")
			(hide yes)
			(effects
				(font
					(size 1.016 1.016)
					(thickness 0.1524)
				)
			)
		)
		(duplicate_pad_numbers_are_jumpers no)
		(fp_line
			(start 2.1336 1.4224)
			(end 2.1336 -1.4224)
			(stroke
				(width 0.1524)
				(type default)
			)
			(layer "F.SilkS")
		)
		(fp_line
			(start 2.1336 -1.4224)
			(end -2.7432 -1.4224)
			(stroke
				(width 0.1524)
				(type default)
			)
			(layer "F.SilkS")
		)
		(fp_line
			(start -2.1844 -0.0508)
			(end -2.7178 0.508)
			(stroke
				(width 0.1524)
				(type default)
			)
			(layer "F.SilkS")
		)
		(fp_line
			(start -2.6289 3.4417)
			(end -2.6289 1.4732)
			(stroke
				(width 0.381)
				(type default)
			)
			(layer "F.SilkS")
		)
		(fp_line
			(start -2.7178 -0.508)
			(end -2.1844 -0.0508)
			(stroke
				(width 0.1524)
				(type default)
			)
			(layer "F.SilkS")
		)
		(fp_line
			(start -2.7432 1.4224)
			(end 2.1336 1.4224)
			(stroke
				(width 0.1524)
				(type default)
			)
			(layer "F.SilkS")
		)
		(fp_line
			(start -2.7432 1.4224)
			(end -2.6416 1.4224)
			(stroke
				(width 0.1524)
				(type default)
			)
			(layer "F.SilkS")
		)
		(fp_line
			(start -2.7432 -1.4224)
			(end -2.7432 1.4224)
			(stroke
				(width 0.1524)
				(type default)
			)
			(layer "F.SilkS")
		)
		(fp_poly
			(pts
				(xy -2.2098 -1.4224) (xy -2.2098 1.4224) (xy 2.2098 1.4224) (xy 2.2098 -1.4224)
			)
			(stroke
				(width 0)
				(type default)
			)
			(fill yes)
			(layer "F.SilkS")
		)
		(fp_rect
			(start -2.450084 2.999994)
			(end 2.450084 -2.999994)
			(stroke
				(width 0)
				(type default)
			)
			(fill no)
			(layer "F.CrtYd")
		)
		(fp_poly
			(pts
				(xy -2.8194 3.6322) (xy -2.8194 -3.6322) (xy 2.8194 -3.6322) (xy 2.8194 1.18364) (xy 2.450084 1.18364)
				(xy 2.450084 -2.999994) (xy -2.450084 -2.999994) (xy -2.450084 2.999994) (xy 2.450084 2.999994)
				(xy 2.450084 1.18618) (xy 2.8194 1.18618) (xy 2.8194 3.6322)
			)
			(stroke
				(width 0)
				(type default)
			)
			(fill no)
			(layer "F.CrtYd")
		)
		(fp_rect
			(start -2.8194 3.6322)
			(end 2.8194 -3.6322)
			(stroke
				(width 0)
				(type default)
			)
			(fill no)
			(layer "F.Fab")
		)
		(pad "1" smd rect
			(at -1.905 2.54 180)
			(size 0.635 1.651)
			(layers "F.Cu" "F.Mask" "F.Paste")
			(net "P5V_HDD17")
		)
		(pad "2" smd rect
			(at -0.635 2.54 180)
			(size 0.635 1.651)
			(layers "F.Cu" "F.Mask" "F.Paste")
			(net "P5V_HDD17")
		)
		(pad "3" smd rect
			(at 0.635 2.54 180)
			(size 0.635 1.651)
			(layers "F.Cu" "F.Mask" "F.Paste")
			(net "P5V_HDD17")
		)
		(pad "4" smd rect
			(at 1.905 2.54 180)
			(size 0.635 1.651)
			(layers "F.Cu" "F.Mask" "F.Paste")
			(net "SW_HDD_P17")
		)
		(pad "5" smd rect
			(at 1.905 -2.54 180)
			(size 0.635 1.651)
			(layers "F.Cu" "F.Mask" "F.Paste")
			(net "P5V_B_2")
		)
		(pad "6" smd rect
			(at 0.635 -2.54 180)
			(size 0.635 1.651)
			(layers "F.Cu" "F.Mask" "F.Paste")
			(net "P5V_B_2")
		)
		(pad "7" smd rect
			(at -0.635 -2.54 180)
			(size 0.635 1.651)
			(layers "F.Cu" "F.Mask" "F.Paste")
			(net "P5V_B_2")
		)
		(pad "8" smd rect
			(at -1.905 -2.54 180)
			(size 0.635 1.651)
			(layers "F.Cu" "F.Mask" "F.Paste")
			(net "P5V_B_2")
		)
	)
)
